# T6G (Grand Teton) — schematic netlist excerpt (pin names and nets, part order shuffled) for the footprints in the layout excerpt that follows; sources: Cadence DE-HDL packaged netlist, KiCad conversion of 04192023_DAF0TMB3IC0_F0TG_MB_C_brd_V02_OCP.brd

R1531  Q_RES  1K 1% EMPTY  pkg 0402LF  page 77 : A = PVDD18_S5_P0 ; B = SPI_CPU0_D1
PR3854  Q_RES  10K 1% CHIP  pkg 0402LF  page 141 : A = P12V_OCP_OV_FB_2 ; B = GND

(kicad_pcb
	(version 20260206)
	(generator "pcbnew")
	(generator_version "10.0")
	(general
		(thickness 1.6)
		(legacy_teardrops no)
	)
	(paper "A4")
	(title_block
		(title "04192023_DAF0TMB3IC0_F0TG_MB_C_brd_V02_OCP.brd")
		(comment 1 "Grand Teton / footprints 2919-2920 of 8354")
	)
	(layers
		(0 "F.Cu" signal "TOP")
		(4 "In1.Cu" signal "GND")
		(6 "In2.Cu" signal "IN1")
		(8 "In3.Cu" signal "GND1")
		(10 "In4.Cu" signal "IN2")
		(12 "In5.Cu" signal "GND2")
		(14 "In6.Cu" signal "IN3")
		(16 "In7.Cu" signal "GND3")
		(18 "In8.Cu" signal "VCC")
		(20 "In9.Cu" signal "VCC1")
		(22 "In10.Cu" signal "GND4")
		(24 "In11.Cu" signal "IN4")
		(26 "In12.Cu" signal "GND5")
		(28 "In13.Cu" signal "IN5")
		(30 "In14.Cu" signal "GND6")
		(32 "In15.Cu" signal "IN6")
		(34 "In16.Cu" signal "GND7")
		(2 "B.Cu" signal "BOTTOM")
		(9 "F.Adhes" user "F.Adhesive")
		(11 "B.Adhes" user "B.Adhesive")
		(13 "F.Paste" user "Package Geometry/Pastemask Top")
		(15 "B.Paste" user "Package Geometry/Pastemask Bottom")
		(5 "F.SilkS" user "Ref Des/Silkscreen Top")
		(7 "B.SilkS" user "Ref Des/Silkscreen Bottom")
		(1 "F.Mask" user "Board Geometry/Soldermask Top")
		(3 "B.Mask" user "Board Geometry/Soldermask Bottom")
		(17 "Dwgs.User" user "User.Drawings")
		(19 "Cmts.User" user "User.Comments")
		(21 "Eco1.User" user "User.Eco1")
		(23 "Eco2.User" user "User.Eco2")
		(25 "Edge.Cuts" user "Board Geometry/Outline")
		(27 "Margin" user)
		(31 "F.CrtYd" user "Package Geometry/Place Bound Top")
		(29 "B.CrtYd" user "Package Geometry/Place Bound Bottom")
		(35 "F.Fab" user "Ref Des/Assembly Top")
		(33 "B.Fab" user "Ref Des/Assembly Bottom")
	)
	(footprint ""
		(layer "F.Cu")
		(at 63.877698 -26.99004 -90)
		(property "Reference" "PR3854"
			(at 0 0 270)
			(layer "F.SilkS")
			(hide yes)
			(effects
				(font
					(size 1.27 1.27)
				)
			)
		)
		(property "Value" ""
			(at 0 0 270)
			(layer "F.Fab")
			(effects
				(font
					(size 1.27 1.27)
				)
			)
		)
		(duplicate_pad_numbers_are_jumpers no)
		(fp_line
			(start -0.7874 0.4064)
			(end -0.7874 -0.4064)
			(stroke
				(width 0.1524)
				(type default)
			)
			(layer "F.SilkS")
		)
		(fp_line
			(start 0.7874 0.4064)
			(end -0.7874 0.4064)
			(stroke
				(width 0.1524)
				(type default)
			)
			(layer "F.SilkS")
		)
		(fp_line
			(start -0.7874 -0.4064)
			(end 0.7874 -0.4064)
			(stroke
				(width 0.1524)
				(type default)
			)
			(layer "F.SilkS")
		)
		(fp_line
			(start 0.7874 -0.4064)
			(end 0.7874 0.4064)
			(stroke
				(width 0.1524)
				(type default)
			)
			(layer "F.SilkS")
		)
		(fp_line
			(start -0.67945 0.3048)
			(end -0.67945 -0.305054)
			(stroke
				(width 0.1)
				(type default)
			)
			(layer "F.Fab")
		)
		(fp_line
			(start -0.12065 0.3048)
			(end -0.67945 0.3048)
			(stroke
				(width 0.1)
				(type default)
			)
			(layer "F.Fab")
		)
		(fp_line
			(start 0.120396 0.3048)
			(end 0.120396 0.2794)
			(stroke
				(width 0.1)
				(type default)
			)
			(layer "F.Fab")
		)
		(fp_line
			(start 0.67945 0.3048)
			(end 0.120396 0.3048)
			(stroke
				(width 0.1)
				(type default)
			)
			(layer "F.Fab")
		)
		(fp_line
			(start -0.12065 0.2794)
			(end -0.12065 0.3048)
			(stroke
				(width 0.1)
				(type default)
			)
			(layer "F.Fab")
		)
		(fp_line
			(start 0.120396 0.2794)
			(end -0.12065 0.2794)
			(stroke
				(width 0.1)
				(type default)
			)
			(layer "F.Fab")
		)
		(fp_line
			(start -0.12065 -0.2794)
			(end 0.12065 -0.2794)
			(stroke
				(width 0.1)
				(type default)
			)
			(layer "F.Fab")
		)
		(fp_line
			(start 0.12065 -0.2794)
			(end 0.12065 -0.3048)
			(stroke
				(width 0.1)
				(type default)
			)
			(layer "F.Fab")
		)
		(fp_line
			(start 0.12065 -0.3048)
			(end 0.67945 -0.3048)
			(stroke
				(width 0.1)
				(type default)
			)
			(layer "F.Fab")
		)
		(fp_line
			(start 0.67945 -0.3048)
			(end 0.67945 0.3048)
			(stroke
				(width 0.1)
				(type default)
			)
			(layer "F.Fab")
		)
		(fp_line
			(start -0.67945 -0.305054)
			(end -0.12065 -0.305054)
			(stroke
				(width 0.1)
				(type default)
			)
			(layer "F.Fab")
		)
		(fp_line
			(start -0.12065 -0.305054)
			(end -0.12065 -0.2794)
			(stroke
				(width 0.1)
				(type default)
			)
			(layer "F.Fab")
		)
		(pad "1" smd circle
			(at -0.40005 0 270)
			(size 0 0)
			(layers "F.Cu" "F.Mask" "F.Paste")
			(net "P12V_OCP_OV_FB_2")
		)
		(pad "2" smd circle
			(at 0.40005 0 270)
			(size 0 0)
			(layers "F.Cu" "F.Mask" "F.Paste")
			(net "GND")
		)
	)
	(footprint ""
		(layer "F.Cu")
		(at 261.62 -143.764 180)
		(property "Reference" "R1531"
			(at 0 0 180)
			(layer "F.SilkS")
			(hide yes)
			(effects
				(font
					(size 1.27 1.27)
				)
			)
		)
		(property "Value" ""
			(at 0 0 180)
			(layer "F.Fab")
			(effects
				(font
					(size 1.27 1.27)
				)
			)
		)
		(duplicate_pad_numbers_are_jumpers no)
		(fp_line
			(start 0.7874 0.4064)
			(end -0.7874 0.4064)
			(stroke
				(width 0.1524)
				(type default)
			)
			(layer "F.SilkS")
		)
		(fp_line
			(start 0.7874 -0.4064)
			(end 0.7874 0.4064)
			(stroke
				(width 0.1524)
				(type default)
			)
			(layer "F.SilkS")
		)
		(fp_line
			(start -0.7874 0.4064)
			(end -0.7874 -0.4064)
			(stroke
				(width 0.1524)
				(type default)
			)
			(layer "F.SilkS")
		)
		(fp_line
			(start -0.7874 -0.4064)
			(end 0.7874 -0.4064)
			(stroke
				(width 0.1524)
				(type default)
			)
			(layer "F.SilkS")
		)
		(fp_line
			(start 0.67945 0.3048)
			(end 0.120396 0.3048)
			(stroke
				(width 0.1)
				(type default)
			)
			(layer "F.Fab")
		)
		(fp_line
			(start 0.67945 -0.3048)
			(end 0.67945 0.3048)
			(stroke
				(width 0.1)
				(type default)
			)
			(layer "F.Fab")
		)
		(fp_line
			(start 0.12065 -0.2794)
			(end 0.12065 -0.3048)
			(stroke
				(width 0.1)
				(type default)
			)
			(layer "F.Fab")
		)
		(fp_line
			(start 0.12065 -0.3048)
			(end 0.67945 -0.3048)
			(stroke
				(width 0.1)
				(type default)
			)
			(layer "F.Fab")
		)
		(fp_line
			(start 0.120396 0.3048)
			(end 0.120396 0.2794)
			(stroke
				(width 0.1)
				(type default)
			)
			(layer "F.Fab")
		)
		(fp_line
			(start 0.120396 0.2794)
			(end -0.12065 0.2794)
			(stroke
				(width 0.1)
				(type default)
			)
			(layer "F.Fab")
		)
		(fp_line
			(start -0.12065 0.3048)
			(end -0.67945 0.3048)
			(stroke
				(width 0.1)
				(type default)
			)
			(layer "F.Fab")
		)
		(fp_line
			(start -0.12065 0.2794)
			(end -0.12065 0.3048)
			(stroke
				(width 0.1)
				(type default)
			)
			(layer "F.Fab")
		)
		(fp_line
			(start -0.12065 -0.2794)
			(end 0.12065 -0.2794)
			(stroke
				(width 0.1)
				(type default)
			)
			(layer "F.Fab")
		)
		(fp_line
			(start -0.12065 -0.305054)
			(end -0.12065 -0.2794)
			(stroke
				(width 0.1)
				(type default)
			)
			(layer "F.Fab")
		)
		(fp_line
			(start -0.67945 0.3048)
			(end -0.67945 -0.305054)
			(stroke
				(width 0.1)
				(type default)
			)
			(layer "F.Fab")
		)
		(fp_line
			(start -0.67945 -0.305054)
			(end -0.12065 -0.305054)
			(stroke
				(width 0.1)
				(type default)
			)
			(layer "F.Fab")
		)
		(pad "1" smd circle
			(at -0.40005 0 180)
			(size 0 0)
			(layers "F.Cu" "F.Mask" "F.Paste")
			(net "PVDD18_S5_P0")
		)
		(pad "2" smd circle
			(at 0.40005 0 180)
			(size 0 0)
			(layers "F.Cu" "F.Mask" "F.Paste")
			(net "SPI_CPU0_D1")
		)
	)
)
